# SCM (Grand Teton) — schematic netlist excerpt (pin names and nets, part order shuffled) for the footprints in the layout excerpt that follows; sources: Cadence DE-HDL packaged netlist, KiCad conversion of 12092022_DA0F0TMDCD0_F0T_Management_Board_D_brd_V3_OCP.brd

R674  Q_RES  0 5% CHIP  pkg 0402LF  page 47 : A = LED_POSTCODE_6 ; B = LED_POSTCODE_6_R1
R170  Q_RES  33.2 1% CHIP  pkg 0402LF  page 13 : A = UART_BMC_5_TXD ; B = UART_BMC_5_TXD_R

(kicad_pcb
	(version 20260206)
	(generator "pcbnew")
	(generator_version "10.0")
	(general
		(thickness 1.6)
		(legacy_teardrops no)
	)
	(paper "A4")
	(title_block
		(title "12092022_DA0F0TMDCD0_F0T_Management_Board_D_brd_V3_OCP.brd")
		(comment 1 "Grand Teton / footprints 845-846 of 1440")
	)
	(layers
		(0 "F.Cu" signal "TOP")
		(4 "In1.Cu" signal "GND")
		(6 "In2.Cu" signal "IN1")
		(8 "In3.Cu" signal "GND1")
		(10 "In4.Cu" signal "IN2")
		(12 "In5.Cu" signal "VCC")
		(14 "In6.Cu" signal "VCC1")
		(16 "In7.Cu" signal "IN3")
		(18 "In8.Cu" signal "GND2")
		(20 "In9.Cu" signal "IN4")
		(22 "In10.Cu" signal "GND3")
		(2 "B.Cu" signal "BOTTOM")
		(9 "F.Adhes" user "F.Adhesive")
		(11 "B.Adhes" user "B.Adhesive")
		(13 "F.Paste" user "Package Geometry/Pastemask Top")
		(15 "B.Paste" user "Package Geometry/Pastemask Bottom")
		(5 "F.SilkS" user "Ref Des/Silkscreen Top")
		(7 "B.SilkS" user "Ref Des/Silkscreen Bottom")
		(1 "F.Mask" user "Board Geometry/Soldermask Top")
		(3 "B.Mask" user "Board Geometry/Soldermask Bottom")
		(17 "Dwgs.User" user "User.Drawings")
		(19 "Cmts.User" user "User.Comments")
		(21 "Eco1.User" user "User.Eco1")
		(23 "Eco2.User" user "User.Eco2")
		(25 "Edge.Cuts" user "Board Geometry/Outline")
		(27 "Margin" user)
		(31 "F.CrtYd" user "Package Geometry/Place Bound Top")
		(29 "B.CrtYd" user "Package Geometry/Place Bound Bottom")
		(35 "F.Fab" user "Ref Des/Assembly Top")
		(33 "B.Fab" user "Ref Des/Assembly Bottom")
	)
	(footprint ""
		(layer "B.Cu")
		(at 74.8538 -33.4518 180)
		(property "Reference" "R674"
			(at 0 0 0)
			(layer "B.SilkS")
			(hide yes)
			(effects
				(font
					(size 1.27 1.27)
				)
				(justify mirror)
			)
		)
		(property "Value" ""
			(at 0 0 0)
			(layer "B.Fab")
			(effects
				(font
					(size 1.27 1.27)
				)
				(justify mirror)
			)
		)
		(duplicate_pad_numbers_are_jumpers no)
		(fp_line
			(start 0.7874 0.4064)
			(end 0.7874 -0.4064)
			(stroke
				(width 0.1524)
				(type default)
			)
			(layer "B.SilkS")
		)
		(fp_line
			(start 0.7874 -0.4064)
			(end -0.7874 -0.4064)
			(stroke
				(width 0.1524)
				(type default)
			)
			(layer "B.SilkS")
		)
		(fp_line
			(start -0.7874 0.4064)
			(end 0.7874 0.4064)
			(stroke
				(width 0.1524)
				(type default)
			)
			(layer "B.SilkS")
		)
		(fp_line
			(start -0.7874 -0.4064)
			(end -0.7874 0.4064)
			(stroke
				(width 0.1524)
				(type default)
			)
			(layer "B.SilkS")
		)
		(fp_line
			(start 0.67945 0.3048)
			(end 0.67945 -0.305054)
			(stroke
				(width 0.1)
				(type default)
			)
			(layer "B.Fab")
		)
		(fp_line
			(start 0.67945 -0.305054)
			(end 0.12065 -0.305054)
			(stroke
				(width 0.1)
				(type default)
			)
			(layer "B.Fab")
		)
		(fp_line
			(start 0.12065 0.3048)
			(end 0.67945 0.3048)
			(stroke
				(width 0.1)
				(type default)
			)
			(layer "B.Fab")
		)
		(fp_line
			(start 0.12065 0.2794)
			(end 0.12065 0.3048)
			(stroke
				(width 0.1)
				(type default)
			)
			(layer "B.Fab")
		)
		(fp_line
			(start 0.12065 -0.2794)
			(end -0.12065 -0.2794)
			(stroke
				(width 0.1)
				(type default)
			)
			(layer "B.Fab")
		)
		(fp_line
			(start 0.12065 -0.305054)
			(end 0.12065 -0.2794)
			(stroke
				(width 0.1)
				(type default)
			)
			(layer "B.Fab")
		)
		(fp_line
			(start -0.120396 0.3048)
			(end -0.120396 0.2794)
			(stroke
				(width 0.1)
				(type default)
			)
			(layer "B.Fab")
		)
		(fp_line
			(start -0.120396 0.2794)
			(end 0.12065 0.2794)
			(stroke
				(width 0.1)
				(type default)
			)
			(layer "B.Fab")
		)
		(fp_line
			(start -0.12065 -0.2794)
			(end -0.12065 -0.3048)
			(stroke
				(width 0.1)
				(type default)
			)
			(layer "B.Fab")
		)
		(fp_line
			(start -0.12065 -0.3048)
			(end -0.67945 -0.3048)
			(stroke
				(width 0.1)
				(type default)
			)
			(layer "B.Fab")
		)
		(fp_line
			(start -0.67945 0.3048)
			(end -0.120396 0.3048)
			(stroke
				(width 0.1)
				(type default)
			)
			(layer "B.Fab")
		)
		(fp_line
			(start -0.67945 -0.3048)
			(end -0.67945 0.3048)
			(stroke
				(width 0.1)
				(type default)
			)
			(layer "B.Fab")
		)
		(pad "1" smd circle
			(at 0.40005 0)
			(size 0 0)
			(layers "B.Cu" "B.Mask" "B.Paste")
			(net "LED_POSTCODE_6")
		)
		(pad "2" smd circle
			(at -0.40005 0)
			(size 0 0)
			(layers "B.Cu" "B.Mask" "B.Paste")
			(net "LED_POSTCODE_6_R1")
		)
	)
	(footprint ""
		(layer "B.Cu")
		(at 65.2018 -34.637726 90)
		(property "Reference" "R170"
			(at 0 0 90)
			(layer "B.SilkS")
			(hide yes)
			(effects
				(font
					(size 1.27 1.27)
				)
				(justify mirror)
			)
		)
		(property "Value" ""
			(at 0 0 90)
			(layer "B.Fab")
			(effects
				(font
					(size 1.27 1.27)
				)
				(justify mirror)
			)
		)
		(duplicate_pad_numbers_are_jumpers no)
		(fp_line
			(start 0.7874 -0.4064)
			(end -0.7874 -0.4064)
			(stroke
				(width 0.1524)
				(type default)
			)
			(layer "B.SilkS")
		)
		(fp_line
			(start -0.7874 -0.4064)
			(end -0.7874 0.4064)
			(stroke
				(width 0.1524)
				(type default)
			)
			(layer "B.SilkS")
		)
		(fp_line
			(start 0.7874 0.4064)
			(end 0.7874 -0.4064)
			(stroke
				(width 0.1524)
				(type default)
			)
			(layer "B.SilkS")
		)
		(fp_line
			(start -0.7874 0.4064)
			(end 0.7874 0.4064)
			(stroke
				(width 0.1524)
				(type default)
			)
			(layer "B.SilkS")
		)
		(fp_line
			(start 0.67945 -0.305054)
			(end 0.12065 -0.305054)
			(stroke
				(width 0.1)
				(type default)
			)
			(layer "B.Fab")
		)
		(fp_line
			(start 0.12065 -0.305054)
			(end 0.12065 -0.2794)
			(stroke
				(width 0.1)
				(type default)
			)
			(layer "B.Fab")
		)
		(fp_line
			(start -0.12065 -0.3048)
			(end -0.67945 -0.3048)
			(stroke
				(width 0.1)
				(type default)
			)
			(layer "B.Fab")
		)
		(fp_line
			(start -0.67945 -0.3048)
			(end -0.67945 0.3048)
			(stroke
				(width 0.1)
				(type default)
			)
			(layer "B.Fab")
		)
		(fp_line
			(start 0.12065 -0.2794)
			(end -0.12065 -0.2794)
			(stroke
				(width 0.1)
				(type default)
			)
			(layer "B.Fab")
		)
		(fp_line
			(start -0.12065 -0.2794)
			(end -0.12065 -0.3048)
			(stroke
				(width 0.1)
				(type default)
			)
			(layer "B.Fab")
		)
		(fp_line
			(start 0.12065 0.2794)
			(end 0.12065 0.3048)
			(stroke
				(width 0.1)
				(type default)
			)
			(layer "B.Fab")
		)
		(fp_line
			(start -0.120396 0.2794)
			(end 0.12065 0.2794)
			(stroke
				(width 0.1)
				(type default)
			)
			(layer "B.Fab")
		)
		(fp_line
			(start 0.67945 0.3048)
			(end 0.67945 -0.305054)
			(stroke
				(width 0.1)
				(type default)
			)
			(layer "B.Fab")
		)
		(fp_line
			(start 0.12065 0.3048)
			(end 0.67945 0.3048)
			(stroke
				(width 0.1)
				(type default)
			)
			(layer "B.Fab")
		)
		(fp_line
			(start -0.120396 0.3048)
			(end -0.120396 0.2794)
			(stroke
				(width 0.1)
				(type default)
			)
			(layer "B.Fab")
		)
		(fp_line
			(start -0.67945 0.3048)
			(end -0.120396 0.3048)
			(stroke
				(width 0.1)
				(type default)
			)
			(layer "B.Fab")
		)
		(pad "1" smd circle
			(at 0.40005 0 270)
			(size 0 0)
			(layers "B.Cu" "B.Mask" "B.Paste")
			(net "UART_BMC_5_TXD")
		)
		(pad "2" smd circle
			(at -0.40005 0 270)
			(size 0 0)
			(layers "B.Cu" "B.Mask" "B.Paste")
			(net "UART_BMC_5_TXD_R")
		)
	)
)
